(kicad_pcb
	(version 20260206)
	(generator "pcbnew")
	(generator_version "10.0")
	(general
		(thickness 1.6)
		(legacy_teardrops no)
	)
	(paper "A4")
	(title_block
		(title "Wiwynn_Tioga_Pass_MB.brd")
		(comment 1 "Tioga Pass / footprints 3335-3341 of 4770")
	)
	(layers
		(0 "F.Cu" signal "TOP")
		(4 "In1.Cu" signal "L2GND")
		(6 "In2.Cu" signal "L3")
		(8 "In3.Cu" signal "L4GND")
		(10 "In4.Cu" signal "L5")
		(12 "In5.Cu" signal "L6GND")
		(14 "In6.Cu" signal "L7VCC")
		(16 "In7.Cu" signal "L8VCC")
		(18 "In8.Cu" signal "L9GND")
		(20 "In9.Cu" signal "L10")
		(22 "In10.Cu" signal "L11GND")
		(24 "In11.Cu" signal "L12")
		(26 "In12.Cu" signal "L13GND")
		(2 "B.Cu" signal "BOTTOM")
		(9 "F.Adhes" user "F.Adhesive")
		(11 "B.Adhes" user "B.Adhesive")
		(13 "F.Paste" user "Package Geometry/Pastemask Top")
		(15 "B.Paste" user "Package Geometry/Pastemask Bottom")
		(5 "F.SilkS" user "Ref Des/Silkscreen Top")
		(7 "B.SilkS" user "Ref Des/Silkscreen Bottom")
		(1 "F.Mask" user "Board Geometry/Soldermask Top")
		(3 "B.Mask" user "Board Geometry/Soldermask Bottom")
		(17 "Dwgs.User" user "User.Drawings")
		(19 "Cmts.User" user "User.Comments")
		(21 "Eco1.User" user "User.Eco1")
		(23 "Eco2.User" user "User.Eco2")
		(25 "Edge.Cuts" user "Board Geometry/Outline")
		(27 "Margin" user)
		(31 "F.CrtYd" user "Package Geometry/Place Bound Top")
		(29 "B.CrtYd" user "Package Geometry/Place Bound Bottom")
		(35 "F.Fab" user "Ref Des/Assembly Top")
		(33 "B.Fab" user "Ref Des/Assembly Bottom")
	)
	(footprint ""
		(layer "B.Cu")
		(at 318.483996 -154.801824 -90)
		(property "Reference" "C4L2"
			(at 0 0 90)
			(layer "B.SilkS")
			(hide yes)
			(effects
				(font
					(size 1.27 1.27)
				)
				(justify mirror)
			)
		)
		(property "Value" ""
			(at 0 0 90)
			(layer "B.Fab")
			(effects
				(font
					(size 1.27 1.27)
				)
				(justify mirror)
			)
		)
		(duplicate_pad_numbers_are_jumpers no)
		(fp_poly
			(pts
				(xy 0.4953 -0.2032) (xy -0.4953 -0.2032) (xy -0.4953 1.6002) (xy 0.4953 1.6002)
			)
			(stroke
				(width 0)
				(type default)
			)
			(fill no)
			(layer "B.CrtYd")
		)
		(fp_line
			(start -0.4953 1.6002)
			(end 0.4953 1.6002)
			(stroke
				(width 0.1)
				(type default)
			)
			(layer "B.Fab")
		)
		(fp_line
			(start 0.4953 1.6002)
			(end 0.4953 -0.2032)
			(stroke
				(width 0.1)
				(type default)
			)
			(layer "B.Fab")
		)
		(fp_line
			(start -0.4953 -0.2032)
			(end -0.4953 1.6002)
			(stroke
				(width 0.1)
				(type default)
			)
			(layer "B.Fab")
		)
		(fp_line
			(start 0.4953 -0.2032)
			(end -0.4953 -0.2032)
			(stroke
				(width 0.1)
				(type default)
			)
			(layer "B.Fab")
		)
		(pad "1" smd rect
			(at 0 0 90)
			(size 0.762 0.889)
			(layers "B.Cu" "B.Mask" "B.Paste")
			(net "PVPP_DEF")
		)
		(pad "2" smd rect
			(at 0 1.397 90)
			(size 0.762 0.889)
			(layers "B.Cu" "B.Mask" "B.Paste")
			(net "GND")
		)
		(zone
			(layer "B.Cu")
			(hatch none 0.5)
			(connect_pads
				(clearance 0)
			)
			(min_thickness 0.25)
			(keepout
				(tracks not_allowed)
				(vias allowed)
				(pads allowed)
				(copperpour not_allowed)
				(footprints allowed)
			)
			(placement
				(enabled no)
				(sheetname "")
			)
			(fill
				(thermal_gap 0.5)
				(thermal_bridge_width 0.5)
				(island_removal_mode 0)
			)
			(polygon
				(pts
					(xy 318.039496 -154.420824) (xy 318.039496 -155.182824) (xy 317.531496 -155.182824) (xy 317.531496 -154.420824)
				)
			)
		)
	)
	(footprint ""
		(layer "B.Cu")
		(at 358.44988 -77.923136 180)
		(property "Reference" "C3P40"
			(at 0 0 0)
			(layer "B.SilkS")
			(hide yes)
			(effects
				(font
					(size 1.27 1.27)
				)
				(justify mirror)
			)
		)
		(property "Value" ""
			(at 0 0 0)
			(layer "B.Fab")
			(effects
				(font
					(size 1.27 1.27)
				)
				(justify mirror)
			)
		)
		(duplicate_pad_numbers_are_jumpers no)
		(fp_poly
			(pts
				(xy -0.3048 -0.1016) (xy -0.3048 0.9906) (xy 0.3048 0.9906) (xy 0.3048 -0.1016)
			)
			(stroke
				(width 0)
				(type default)
			)
			(fill no)
			(layer "B.CrtYd")
		)
		(fp_line
			(start 0.3048 0.9906)
			(end -0.3048 0.9906)
			(stroke
				(width 0.1)
				(type default)
			)
			(layer "B.Fab")
		)
		(fp_line
			(start 0.3048 -0.1016)
			(end 0.3048 0.9906)
			(stroke
				(width 0.1)
				(type default)
			)
			(layer "B.Fab")
		)
		(fp_line
			(start -0.3048 0.9906)
			(end -0.3048 -0.1016)
			(stroke
				(width 0.1)
				(type default)
			)
			(layer "B.Fab")
		)
		(fp_line
			(start -0.3048 -0.1016)
			(end 0.3048 -0.1016)
			(stroke
				(width 0.1)
				(type default)
			)
			(layer "B.Fab")
		)
		(pad "1" smd rect
			(at 0 0)
			(size 0.508 0.508)
			(layers "B.Cu" "B.Mask" "B.Paste")
			(net "P3E_CPU0_PE1_SS_TXN<7>")
		)
		(pad "2" smd rect
			(at 0 0.889)
			(size 0.508 0.508)
			(layers "B.Cu" "B.Mask" "B.Paste")
			(net "P3E_CPU0_PE1_PCH_TXN<7>")
		)
		(zone
			(layer "B.Cu")
			(hatch none 0.5)
			(connect_pads
				(clearance 0)
			)
			(min_thickness 0.25)
			(keepout
				(tracks not_allowed)
				(vias allowed)
				(pads allowed)
				(copperpour not_allowed)
				(footprints allowed)
			)
			(placement
				(enabled no)
				(sheetname "")
			)
			(fill
				(thermal_gap 0.5)
				(thermal_bridge_width 0.5)
				(island_removal_mode 0)
			)
			(polygon
				(pts
					(xy 358.19588 -78.558136) (xy 358.70388 -78.558136) (xy 358.70388 -78.177136) (xy 358.19588 -78.177136)
				)
			)
		)
		(zone
			(layer "B.Cu")
			(hatch none 0.5)
			(connect_pads
				(clearance 0)
			)
			(min_thickness 0.25)
			(keepout
				(tracks allowed)
				(vias not_allowed)
				(pads allowed)
				(copperpour not_allowed)
				(footprints allowed)
			)
			(placement
				(enabled no)
				(sheetname "")
			)
			(fill
				(thermal_gap 0.5)
				(thermal_bridge_width 0.5)
				(island_removal_mode 0)
			)
			(polygon
				(pts
					(xy 358.19588 -78.177136) (xy 358.70388 -78.177136) (xy 358.70388 -78.558136) (xy 358.19588 -78.558136)
				)
			)
		)
	)
	(footprint ""
		(layer "B.Cu")
		(at 176.25568 -82.677 -90)
		(property "Reference" "R6P12"
			(at 0 0 90)
			(layer "B.SilkS")
			(hide yes)
			(effects
				(font
					(size 1.27 1.27)
				)
				(justify mirror)
			)
		)
		(property "Value" ""
			(at 0 0 90)
			(layer "B.Fab")
			(effects
				(font
					(size 1.27 1.27)
				)
				(justify mirror)
			)
		)
		(duplicate_pad_numbers_are_jumpers no)
		(fp_poly
			(pts
				(xy 0.2794 -0.1016) (xy -0.2794 -0.1016) (xy -0.2794 0.9906) (xy 0.2794 0.9906)
			)
			(stroke
				(width 0)
				(type default)
			)
			(fill no)
			(layer "B.CrtYd")
		)
		(fp_line
			(start -0.2794 0.9906)
			(end -0.2794 -0.1016)
			(stroke
				(width 0.1)
				(type default)
			)
			(layer "B.Fab")
		)
		(fp_line
			(start 0.2794 0.9906)
			(end -0.2794 0.9906)
			(stroke
				(width 0.1)
				(type default)
			)
			(layer "B.Fab")
		)
		(fp_line
			(start -0.2794 -0.1016)
			(end 0.2794 -0.1016)
			(stroke
				(width 0.1)
				(type default)
			)
			(layer "B.Fab")
		)
		(fp_line
			(start 0.2794 -0.1016)
			(end 0.2794 0.9906)
			(stroke
				(width 0.1)
				(type default)
			)
			(layer "B.Fab")
		)
		(pad "1" smd rect
			(at 0 0 90)
			(size 0.508 0.508)
			(layers "B.Cu" "B.Mask" "B.Paste")
			(net "CLK_100M_CPU0_BCLK2_DN")
		)
		(pad "2" smd rect
			(at 0 0.889 90)
			(size 0.508 0.508)
			(layers "B.Cu" "B.Mask" "B.Paste")
			(net "GND")
		)
		(zone
			(layer "B.Cu")
			(hatch none 0.5)
			(connect_pads
				(clearance 0)
			)
			(min_thickness 0.25)
			(keepout
				(tracks not_allowed)
				(vias allowed)
				(pads allowed)
				(copperpour not_allowed)
				(footprints allowed)
			)
			(placement
				(enabled no)
				(sheetname "")
			)
			(fill
				(thermal_gap 0.5)
				(thermal_bridge_width 0.5)
				(island_removal_mode 0)
			)
			(polygon
				(pts
					(xy 175.62068 -82.423) (xy 175.62068 -82.931) (xy 176.00168 -82.931) (xy 176.00168 -82.423)
				)
			)
		)
		(zone
			(layer "B.Cu")
			(hatch none 0.5)
			(connect_pads
				(clearance 0)
			)
			(min_thickness 0.25)
			(keepout
				(tracks allowed)
				(vias not_allowed)
				(pads allowed)
				(copperpour not_allowed)
				(footprints allowed)
			)
			(placement
				(enabled no)
				(sheetname "")
			)
			(fill
				(thermal_gap 0.5)
				(thermal_bridge_width 0.5)
				(island_removal_mode 0)
			)
			(polygon
				(pts
					(xy 176.00168 -82.423) (xy 176.00168 -82.931) (xy 175.62068 -82.931) (xy 175.62068 -82.423)
				)
			)
		)
	)
	(footprint ""
		(layer "B.Cu")
		(at 169.799 -85.344)
		(property "Reference" "C6P4"
			(at 0 0 0)
			(layer "B.SilkS")
			(hide yes)
			(effects
				(font
					(size 1.27 1.27)
				)
				(justify mirror)
			)
		)
		(property "Value" ""
			(at 0 0 0)
			(layer "B.Fab")
			(effects
				(font
					(size 1.27 1.27)
				)
				(justify mirror)
			)
		)
		(duplicate_pad_numbers_are_jumpers no)
		(fp_poly
			(pts
				(xy -0.3048 -0.1016) (xy -0.3048 0.9906) (xy 0.3048 0.9906) (xy 0.3048 -0.1016)
			)
			(stroke
				(width 0)
				(type default)
			)
			(fill no)
			(layer "B.CrtYd")
		)
		(fp_line
			(start -0.3048 -0.1016)
			(end 0.3048 -0.1016)
			(stroke
				(width 0.1)
				(type default)
			)
			(layer "B.Fab")
		)
		(fp_line
			(start -0.3048 0.9906)
			(end -0.3048 -0.1016)
			(stroke
				(width 0.1)
				(type default)
			)
			(layer "B.Fab")
		)
		(fp_line
			(start 0.3048 -0.1016)
			(end 0.3048 0.9906)
			(stroke
				(width 0.1)
				(type default)
			)
			(layer "B.Fab")
		)
		(fp_line
			(start 0.3048 0.9906)
			(end -0.3048 0.9906)
			(stroke
				(width 0.1)
				(type default)
			)
			(layer "B.Fab")
		)
		(pad "1" smd rect
			(at 0 0 180)
			(size 0.508 0.508)
			(layers "B.Cu" "B.Mask" "B.Paste")
			(net "P3V3_DB1200")
		)
		(pad "2" smd rect
			(at 0 0.889 180)
			(size 0.508 0.508)
			(layers "B.Cu" "B.Mask" "B.Paste")
			(net "GND")
		)
		(zone
			(layer "B.Cu")
			(hatch none 0.5)
			(connect_pads
				(clearance 0)
			)
			(min_thickness 0.25)
			(keepout
				(tracks allowed)
				(vias not_allowed)
				(pads allowed)
				(copperpour not_allowed)
				(footprints allowed)
			)
			(placement
				(enabled no)
				(sheetname "")
			)
			(fill
				(thermal_gap 0.5)
				(thermal_bridge_width 0.5)
				(island_removal_mode 0)
			)
			(polygon
				(pts
					(xy 170.053 -85.09) (xy 169.545 -85.09) (xy 169.545 -84.709) (xy 170.053 -84.709)
				)
			)
		)
		(zone
			(layer "B.Cu")
			(hatch none 0.5)
			(connect_pads
				(clearance 0)
			)
			(min_thickness 0.25)
			(keepout
				(tracks not_allowed)
				(vias allowed)
				(pads allowed)
				(copperpour not_allowed)
				(footprints allowed)
			)
			(placement
				(enabled no)
				(sheetname "")
			)
			(fill
				(thermal_gap 0.5)
				(thermal_bridge_width 0.5)
				(island_removal_mode 0)
			)
			(polygon
				(pts
					(xy 170.053 -84.709) (xy 169.545 -84.709) (xy 169.545 -85.09) (xy 170.053 -85.09)
				)
			)
		)
	)
	(footprint ""
		(layer "B.Cu")
		(at 409.2702 -126.2888 90)
		(property "Reference" "FB2M1"
			(at 0 0 90)
			(layer "B.SilkS")
			(hide yes)
			(effects
				(font
					(size 1.27 1.27)
				)
				(justify mirror)
			)
		)
		(property "Value" ""
			(at 0 0 90)
			(layer "B.Fab")
			(effects
				(font
					(size 1.27 1.27)
				)
				(justify mirror)
			)
		)
		(duplicate_pad_numbers_are_jumpers no)
		(fp_poly
			(pts
				(xy 0.15113 -0.47498) (xy -1.59893 -0.47498) (xy -1.59893 0.47498) (xy 0.15113 0.47498)
			)
			(stroke
				(width 0)
				(type default)
			)
			(fill no)
			(layer "B.CrtYd")
		)
		(fp_line
			(start 0.15113 -0.47498)
			(end -1.59893 -0.47498)
			(stroke
				(width 0.1)
				(type default)
			)
			(layer "B.Fab")
		)
		(fp_line
			(start -1.59893 -0.47498)
			(end -1.59893 0.47498)
			(stroke
				(width 0.1)
				(type default)
			)
			(layer "B.Fab")
		)
		(fp_line
			(start 0.15113 0.47498)
			(end 0.15113 -0.47498)
			(stroke
				(width 0.1)
				(type default)
			)
			(layer "B.Fab")
		)
		(fp_line
			(start -1.59893 0.47498)
			(end 0.15113 0.47498)
			(stroke
				(width 0.1)
				(type default)
			)
			(layer "B.Fab")
		)
		(pad "1" smd rect
			(at 0 0 270)
			(size 0.9398 0.9398)
			(layers "B.Cu" "B.Mask" "B.Paste")
			(net "P1V05_PCH_STBY")
		)
		(pad "2" smd rect
			(at -1.4478 0 270)
			(size 0.9398 0.9398)
			(layers "B.Cu" "B.Mask" "B.Paste")
			(net "P1V05_PCH_STBY_WM20_PLL")
		)
		(zone
			(layer "B.Cu")
			(hatch none 0.5)
			(connect_pads
				(clearance 0)
			)
			(min_thickness 0.25)
			(keepout
				(tracks not_allowed)
				(vias allowed)
				(pads allowed)
				(copperpour not_allowed)
				(footprints allowed)
			)
			(placement
				(enabled no)
				(sheetname "")
			)
			(fill
				(thermal_gap 0.5)
				(thermal_bridge_width 0.5)
				(island_removal_mode 0)
			)
			(polygon
				(pts
					(xy 409.7401 -125.8189) (xy 408.8003 -125.8189) (xy 408.8003 -125.3109) (xy 409.7401 -125.3109)
				)
			)
		)
		(zone
			(layer "B.Cu")
			(hatch none 0.5)
			(connect_pads
				(clearance 0)
			)
			(min_thickness 0.25)
			(keepout
				(tracks allowed)
				(vias not_allowed)
				(pads allowed)
				(copperpour not_allowed)
				(footprints allowed)
			)
			(placement
				(enabled no)
				(sheetname "")
			)
			(fill
				(thermal_gap 0.5)
				(thermal_bridge_width 0.5)
				(island_removal_mode 0)
			)
			(polygon
				(pts
					(xy 409.7401 -125.8189) (xy 408.8003 -125.8189) (xy 408.8003 -125.3109) (xy 409.7401 -125.3109)
				)
			)
		)
	)
	(footprint ""
		(layer "B.Cu")
		(at 28.801568 -134.874 180)
		(property "Reference" "R9M1"
			(at 0 0 0)
			(layer "B.SilkS")
			(hide yes)
			(effects
				(font
					(size 1.27 1.27)
				)
				(justify mirror)
			)
		)
		(property "Value" ""
			(at 0 0 0)
			(layer "B.Fab")
			(effects
				(font
					(size 1.27 1.27)
				)
				(justify mirror)
			)
		)
		(duplicate_pad_numbers_are_jumpers no)
		(fp_poly
			(pts
				(xy 0.2794 -0.1016) (xy -0.2794 -0.1016) (xy -0.2794 0.9906) (xy 0.2794 0.9906)
			)
			(stroke
				(width 0)
				(type default)
			)
			(fill no)
			(layer "B.CrtYd")
		)
		(fp_line
			(start 0.2794 0.9906)
			(end -0.2794 0.9906)
			(stroke
				(width 0.1)
				(type default)
			)
			(layer "B.Fab")
		)
		(fp_line
			(start 0.2794 -0.1016)
			(end 0.2794 0.9906)
			(stroke
				(width 0.1)
				(type default)
			)
			(layer "B.Fab")
		)
		(fp_line
			(start -0.2794 0.9906)
			(end -0.2794 -0.1016)
			(stroke
				(width 0.1)
				(type default)
			)
			(layer "B.Fab")
		)
		(fp_line
			(start -0.2794 -0.1016)
			(end 0.2794 -0.1016)
			(stroke
				(width 0.1)
				(type default)
			)
			(layer "B.Fab")
		)
		(pad "1" smd rect
			(at 0 0)
			(size 0.508 0.508)
			(layers "B.Cu" "B.Mask" "B.Paste")
			(net "PVDDQ_KLM")
		)
		(pad "2" smd rect
			(at 0 0.889)
			(size 0.508 0.508)
			(layers "B.Cu" "B.Mask" "B.Paste")
			(net "M_K_VREF")
		)
		(zone
			(layer "B.Cu")
			(hatch none 0.5)
			(connect_pads
				(clearance 0)
			)
			(min_thickness 0.25)
			(keepout
				(tracks not_allowed)
				(vias allowed)
				(pads allowed)
				(copperpour not_allowed)
				(footprints allowed)
			)
			(placement
				(enabled no)
				(sheetname "")
			)
			(fill
				(thermal_gap 0.5)
				(thermal_bridge_width 0.5)
				(island_removal_mode 0)
			)
			(polygon
				(pts
					(xy 28.547568 -135.509) (xy 29.055568 -135.509) (xy 29.055568 -135.128) (xy 28.547568 -135.128)
				)
			)
		)
		(zone
			(layer "B.Cu")
			(hatch none 0.5)
			(connect_pads
				(clearance 0)
			)
			(min_thickness 0.25)
			(keepout
				(tracks allowed)
				(vias not_allowed)
				(pads allowed)
				(copperpour not_allowed)
				(footprints allowed)
			)
			(placement
				(enabled no)
				(sheetname "")
			)
			(fill
				(thermal_gap 0.5)
				(thermal_bridge_width 0.5)
				(island_removal_mode 0)
			)
			(polygon
				(pts
					(xy 28.547568 -135.128) (xy 29.055568 -135.128) (xy 29.055568 -135.509) (xy 28.547568 -135.509)
				)
			)
		)
	)
	(footprint ""
		(layer "B.Cu")
		(at 18.0594 -149.5044 -90)
		(property "Reference" "C9L4"
			(at -1.97993 9.0424 0)
			(unlocked yes)
			(layer "B.SilkS")
			(effects
				(font
					(size 0.7874 0.5842)
					(thickness 0.1524)
				)
				(justify mirror)
			)
		)
		(property "Value" ""
			(at 0 0 90)
			(layer "B.Fab")
			(effects
				(font
					(size 1.27 1.27)
				)
				(justify mirror)
			)
		)
		(duplicate_pad_numbers_are_jumpers no)
		(fp_line
			(start -2.286 7.366)
			(end -1.600708 7.366)
			(stroke
				(width 0.1524)
				(type default)
			)
			(layer "B.SilkS")
		)
		(fp_line
			(start -2.286 7.366)
			(end -2.286 1.63195)
			(stroke
				(width 0.1524)
				(type default)
			)
			(layer "B.SilkS")
		)
		(fp_line
			(start 2.286 7.366)
			(end 1.60147 7.366)
			(stroke
				(width 0.1524)
				(type default)
			)
			(layer "B.SilkS")
		)
		(fp_line
			(start 2.286 7.366)
			(end 2.286 1.632712)
			(stroke
				(width 0.1524)
				(type default)
			)
			(layer "B.SilkS")
		)
		(fp_line
			(start -2.504948 1.633728)
			(end -1.6002 1.633728)
			(stroke
				(width 0.1524)
				(type default)
			)
			(layer "B.SilkS")
		)
		(fp_line
			(start 2.563114 1.633728)
			(end 1.6002 1.633728)
			(stroke
				(width 0.1524)
				(type default)
			)
			(layer "B.SilkS")
		)
		(fp_line
			(start -2.504948 -1.616456)
			(end -2.504948 1.633728)
			(stroke
				(width 0.1524)
				(type default)
			)
			(layer "B.SilkS")
		)
		(fp_line
			(start -1.6002 -1.616456)
			(end -2.504948 -1.616456)
			(stroke
				(width 0.1524)
				(type default)
			)
			(layer "B.SilkS")
		)
		(fp_line
			(start 1.6002 -1.616456)
			(end 2.563114 -1.616456)
			(stroke
				(width 0.1524)
				(type default)
			)
			(layer "B.SilkS")
		)
		(fp_line
			(start 2.563114 -1.616456)
			(end 2.563114 1.633728)
			(stroke
				(width 0.1524)
				(type default)
			)
			(layer "B.SilkS")
		)
		(fp_rect
			(start 2.286 -0.254)
			(end -2.286 7.366)
			(stroke
				(width 0)
				(type default)
			)
			(fill no)
			(layer "B.CrtYd")
		)
		(fp_line
			(start -2.286 7.366)
			(end 2.286 7.366)
			(stroke
				(width 0.1)
				(type default)
			)
			(layer "B.Fab")
		)
		(fp_line
			(start 2.286 7.366)
			(end 2.286 -0.254)
			(stroke
				(width 0.1)
				(type default)
			)
			(layer "B.Fab")
		)
		(fp_line
			(start -2.286 -0.254)
			(end -2.286 7.366)
			(stroke
				(width 0.1)
				(type default)
			)
			(layer "B.Fab")
		)
		(fp_line
			(start 2.286 -0.254)
			(end -2.286 -0.254)
			(stroke
				(width 0.1)
				(type default)
			)
			(layer "B.Fab")
		)
		(pad "1" smd rect
			(at 0 0 90)
			(size 2.54 3.048)
			(layers "B.Cu" "B.Mask" "B.Paste")
			(net "PVDDQ_KLM")
		)
		(pad "2" smd rect
			(at 0 7.112 90)
			(size 2.54 3.048)
			(layers "B.Cu" "B.Mask" "B.Paste")
			(net "GND")
		)
	)
)
